;LEADER: 12 
;HEADER: 
;CODE  : ASCII 
;FILE  : DA0T6MTH8C0_t6m_tray_bp_c_brd_103112_274-1-8.drl for board DA0T6MTH8C0_t6m_tray_bp_c_brd_103112_274.brd ... layers TOP and BOTTOM
;   Holesize 1. = 10.000000 Tolerance = +3.000000/-3.000000 PLATED MILS Quantity = 444
;   Holesize 2. = 20.000000 Tolerance = +2.000000/-2.000000 PLATED MILS Quantity = 216
;   Holesize 3. = 20.000000 Tolerance = +3.000000/-3.000000 PLATED MILS Quantity = 297
;   Holesize 4. = 22.000000 Tolerance = +3.000000/-3.000000 PLATED MILS Quantity = 16
;   Holesize 5. = 30.000000 Tolerance = +2.000000/-2.000000 PLATED MILS Quantity = 48
;   Holesize 6. = 33.000000 Tolerance = +2.000000/-2.000000 PLATED MILS Quantity = 4
;   Holesize 7. = 35.000000 Tolerance = +3.000000/-3.000000 PLATED MILS Quantity = 32
;   Holesize 8. = 37.000000 Tolerance = +2.000000/-2.000000 PLATED MILS Quantity = 36
;   Holesize 9. = 38.000000 Tolerance = +3.000000/-3.000000 PLATED MILS Quantity = 12
;   Holesize 10. = 41.000000 Tolerance = +2.000000/-2.000000 PLATED MILS Quantity = 40
;   Holesize 11. = 43.000000 Tolerance = +3.000000/-3.000000 PLATED MILS Quantity = 18
;   Holesize 12. = 46.000000 Tolerance = +3.000000/-3.000000 PLATED MILS Quantity = 8
;   Holesize 13. = 62.000000 Tolerance = +3.000000/-3.000000 PLATED MILS Quantity = 4
;   Holesize 14. = 80.000000 Tolerance = +3.000000/-3.000000 PLATED MILS Quantity = 12
;   Holesize 15. = 99.000000 Tolerance = +3.000000/-3.000000 PLATED MILS Quantity = 8
;   Holesize 16. = 158.000000 Tolerance = +3.000000/-3.000000 PLATED MILS Quantity = 12
;   Holesize 17. = 42.000000 Tolerance = +2.000000/-2.000000 NON_PLATED MILS Quantity = 2
;   Holesize 18. = 43.000000 Tolerance = +2.000000/-2.000000 NON_PLATED MILS Quantity = 2
;   Holesize 19. = 63.000000 Tolerance = +2.000000/-2.000000 NON_PLATED MILS Quantity = 12
;   Holesize 20. = 85.000000 Tolerance = +2.000000/-2.000000 NON_PLATED MILS Quantity = 2
;   Holesize 21. = 128.000000 Tolerance = +2.000000/-2.000000 NON_PLATED MILS Quantity = 4
;   Holesize 22. = 138.000000 Tolerance = +2.000000/-2.000000 NON_PLATED MILS Quantity = 6
;   Holesize 23. = 142.000000 Tolerance = +2.000000/-2.000000 NON_PLATED MILS Quantity = 2
%
G90
X0115400Y0120270
X0111500Y0129900
X0119700Y0132400
X0155500Y0164800
X0129000Y0164800
X0141400Y0164800
X0064500Y0165200
X0089400Y0165300
X0105800Y0165400
X0114300Y0134900
X0108900Y0137300
X0119800Y0124390
X0099100Y0127470
X0125000Y0126400
X0107390Y0125110
X0132500Y0110100
X0106958Y0068500
X0116958Y0068600
X0121958Y0070900
X0111958Y0073600
X0102400Y0059600
X0107500Y0059500
X0114400Y0059700
X0120500Y0059400
X0106958Y0082142
X0112158Y0082342
X0117158Y0082542
X0122758Y0082442
X0125558Y0079642
X0102590Y0115680
X0128600Y0114510
X0183300Y0164700
X0169200Y0165200
X0346906Y0137693
X0347350Y0143750
X0350700Y0121642
X0345900Y0125100
X0412800Y0016200
X0400100Y0013900
X0356861Y0102961
X0357600Y0108561
X0357800Y0114657
X0404400Y0006800
X0346200Y0102500
X0345400Y0107600
X0346800Y0113500
X0357600Y0097000
X0362500Y0097100
X0410200Y0006700
X0414900Y0006500
X0417900Y0006700
X0414055Y0046200
X0410906Y0046100
X0399882Y0079318
X0406181Y0082300
X0409331Y0088600
X0452100Y0097000
X0421929Y0078400
X0451100Y0081400
X0412300Y0085600
X0415630Y0080700
X0453300Y0086800
X0403032Y0089532
X0452000Y0102200
X0412480Y0080900
X0453900Y0092300
X0453480Y0036200
X0447880Y0036200
X0400531Y0021960
X0405531Y0021960
X0463435Y0079865
X0455400Y0038600
X0455400Y0034000
X0446000Y0033900
X0446000Y0038400
X0426200Y0078100
X0426654Y0046100
X0417205Y0046100
X0407756Y0046100
X0408200Y0019900
X0408200Y0023500
X0396732Y0078932
X0398307Y0046100
X0397800Y0019500
X0397800Y0023600
X0398307Y0035000
X0407600Y0035000
X0417205Y0035000
X0426500Y0035000
X0367200Y0124000
X0526612Y0142000
X0549174Y0089400
X0511600Y0108000
X0466300Y0100900
X0488800Y0093800
X0466100Y0083258
X0466200Y0087558
X0523300Y0020580
X0655200Y0004100
X0465600Y0055900
X0477630Y0088900
X0488000Y0089800
X0546024Y0079200
X0547599Y0046100
X0557048Y0046100
X0525600Y0022600
X0520900Y0022500
X0505700Y0090200
X0547599Y0035000
X0556900Y0035000
X0567500Y0007300
X0571500Y0007500
X0575600Y0007600
X0560198Y0046100
X0563347Y0046100
X0582416Y0016466
X0488800Y0073700
X0516500Y0087442
X0552324Y0078500
X0520439Y0091000
X0558623Y0079200
X0519400Y0096400
X0561772Y0080800
X0525700Y0099300
X0659310Y0072900
X0615500Y0105157
X0604400Y0096000
X0604200Y0107400
X0615500Y0100157
X0563800Y0087700
X0523300Y0015580
X0568721Y0022500
X0573721Y0022500
X0507200Y0004200
X0490200Y0004000
X0474500Y0003900
X0648300Y0055600
X0574371Y0078400
X0566497Y0035000
X0575800Y0035000
X0567000Y0024400
X0575800Y0024300
X0575900Y0020800
X0567100Y0020500
X0563100Y0007200
X0520800Y0013800
X0525600Y0013900
X0661600Y0075900
X0625700Y0090100
X0625600Y0095400
X0626100Y0099900
X0626600Y0106100
X0651100Y0091100
X0651500Y0094700
X0659390Y0117490
X0658400Y0102500
X0566497Y0046100
X0575946Y0046100
X0559425Y0013575
X0622658Y0112158
X0564922Y0081900
X0615600Y0095139
X0568072Y0081500
X0614900Y0090157
X0571221Y0079700
X0654400Y0097100
X0654400Y0092100
X0617949Y0147000
X0626173Y0148400
X0622200Y0120258
X0661614Y0121000
X0755410Y0124730
X0685612Y0129600
X0680612Y0129600
X0760410Y0124730
X0694961Y0122030
X0689961Y0122030
X0754300Y0121400
X0723500Y0118900
X0687736Y0118700
X0678288Y0122700
X0667500Y0126200
X0680900Y0133200
X0685600Y0133200
X0666614Y0121000
X0750905Y0120452
X0745905Y0120452
X0676063Y0125930
X0671063Y0125930
X0672638Y0093290
X0677638Y0093290
X0756929Y0072900
X0761929Y0072900
X0664310Y0072900
X0701670Y0092100
X0701670Y0097100
X0681600Y0055500
X0665100Y0055900
X0730900Y0108900
X0722400Y0102300
X0667200Y0075700
X0680300Y0075600
X0753100Y0075100
X0670414Y0096486
X0679862Y0096538
X0689311Y0096311
X0689723Y0089400
X0698400Y0090300
X0745256Y0096044
X0735807Y0096593
X0740300Y0087300
X0754704Y0096196
X0668839Y0117661
X0697185Y0117385
X0701732Y0101968
X0731950Y0111850
X0743681Y0117400
X0753130Y0117300
X0762578Y0117300
X0725310Y0115390
X0730310Y0115390
X0729400Y0105600
X0724400Y0105600
X0747480Y0092830
X0752480Y0092830
X0701100Y0016900
X0778200Y0097130
X0778200Y0092130
X0688800Y0004100
X0765600Y0074800
X0764153Y0096153
X0774600Y0090300
X0772027Y0117300
X0776032Y0101968
X0769803Y0120330
X0764803Y0120330
X0764000Y0124700
X1227100Y0102861
X1227000Y0108361
X1226900Y0114043
X1216400Y0102600
X1216500Y0108300
X1216700Y0114400
X1218000Y0099100
X1223200Y0099000
X1229800Y0096400
X1238900Y0123300
X1238100Y0127900
X1217405Y0143895
X1211200Y0144900
X1219400Y0123900
X1219600Y0129400
X1226900Y0119561
X1216500Y0119500
X1358600Y0073700
X1335600Y0096500
X1345100Y0105500
X1269961Y0078400
X1429525Y0013775
X1282559Y0085700
X1322500Y0087800
X1276260Y0079000
X1285709Y0084300
X1321500Y0082600
X1279410Y0087200
X1329500Y0081400
X1321400Y0092800
X1280985Y0046200
X1288859Y0078400
X1323000Y0099239
X1273111Y0089100
X1333400Y0082900
X1284134Y0046100
X1292008Y0080192
X1454600Y0017600
X1393379Y0015580
X1275610Y0021960
X1317959Y0036200
X1376300Y0004000
X1335300Y0055600
X1340400Y0090800
X1325279Y0033800
X1325279Y0038600
X1315979Y0033900
X1315879Y0038200
X1295158Y0079158
X1277835Y0046100
X1287284Y0046100
X1296733Y0046100
X1278700Y0023000
X1278700Y0019800
X1266811Y0078300
X1268386Y0046100
X1267700Y0019700
X1267700Y0022900
X1433700Y0008000
X1395679Y0013900
X1390879Y0013800
X1359000Y0091000
X1438000Y0008100
X1442400Y0008200
X1446300Y0008300
X1268386Y0035000
X1287284Y0035000
X1277700Y0035000
X1296600Y0035000
X1270610Y0021960
X1323559Y0036200
X1358200Y0069000
X1371600Y0096000
X1430277Y0046100
X1429400Y0088500
X1268700Y0014000
X1289775Y0011975
X1433426Y0046100
X1391000Y0092400
X1428702Y0079002
X1438151Y0081100
X1389900Y0097600
X1431851Y0080200
X1441300Y0079100
X1395200Y0099500
X1435001Y0081700
X1434200Y0088100
X1387400Y0087242
X1422403Y0078400
X1438800Y0022500
X1393379Y0020580
X1443800Y0022500
X1344700Y0004100
X1360600Y0004000
X1273000Y0006100
X1444450Y0078300
X1436576Y0035000
X1445900Y0035000
X1445700Y0024400
X1445900Y0020800
X1436500Y0020700
X1436500Y0023900
X1416103Y0078400
X1427000Y0035000
X1417678Y0035000
X1390979Y0022500
X1395679Y0022600
X1371600Y0086463
X1427127Y0046100
X1417678Y0046100
X1436576Y0046100
X1446025Y0046100
X1285800Y0005900
X1280900Y0005900
X1276700Y0005900
X1487600Y0147000
X1492042Y0126358
X1495800Y0147800
X1560039Y0122030
X1536692Y0121000
X1541141Y0125930
X1537579Y0126200
X1555679Y0133200
X1548366Y0122700
X1557814Y0118700
X1550979Y0133200
X1550690Y0129600
X1546141Y0125930
X1555690Y0129600
X1531692Y0121000
X1474200Y0106600
X1472400Y0102700
X1484800Y0109357
X1492300Y0117558
X1485000Y0098057
X1484700Y0093057
X1484900Y0103257
X1551800Y0055700
X1535300Y0055800
X1518200Y0055600
X1531679Y0075900
X1521179Y0091100
X1521579Y0094700
X1495000Y0092800
X1494200Y0097800
X1494500Y0102700
X1494700Y0111200
X1529468Y0117490
X1538917Y0117661
X1540492Y0096486
X1528478Y0102500
X1559389Y0096311
X1549940Y0096538
X1537279Y0075700
X1550500Y0075500
X1559802Y0089400
X1529388Y0072900
X1547716Y0093290
X1534388Y0072900
X1542716Y0093290
X1524478Y0092100
X1524478Y0097100
X1570800Y0018900
X1648278Y0092130
X1595388Y0115390
X1632007Y0072900
X1627007Y0072900
X1559000Y0004200
X1527200Y0003800
X1600900Y0108700
X1592900Y0101700
X1644679Y0090300
X1568479Y0090300
X1567263Y0117385
X1571810Y0101968
X1646110Y0101968
X1632656Y0117300
X1642105Y0117300
X1634231Y0096153
X1624782Y0096196
X1615334Y0096044
X1605885Y0096593
X1602028Y0111850
X1613759Y0117400
X1623208Y0117300
X1610379Y0087300
X1623179Y0075100
X1635679Y0074800
X1622558Y0092830
X1617558Y0092830
X1600388Y0115390
X1571748Y0097100
X1594478Y0105600
X1599478Y0105600
X1571748Y0092100
X1648278Y0097130
X1634881Y0120330
X1615983Y0120452
X1565039Y0122030
X1593300Y0119000
X1624300Y0121500
X1634179Y0124300
X1630488Y0124730
X1639881Y0120330
X1625488Y0124730
X1620983Y0120452
X1676100Y0078900
M00
X0506024Y0019292
X0498150Y0018898
X0490276Y0019292
X0482402Y0018898
X0474528Y0019292
X0466654Y0018898
X0506024Y0024803
X0498150Y0024410
X0490276Y0024803
X0482402Y0024410
X0474528Y0024803
X0466654Y0024410
X0506024Y0030315
X0498150Y0029922
X0490276Y0030315
X0482402Y0029922
X0474528Y0030315
X0466654Y0029922
X0506024Y0035827
X0498150Y0035433
X0490276Y0035827
X0482402Y0035433
X0474528Y0035827
X0466654Y0035433
X0506024Y0041339
X0498150Y0040945
X0490276Y0041339
X0482402Y0040945
X0474528Y0041339
X0466654Y0040945
X0506024Y0046851
X0498150Y0046457
X0490276Y0046851
X0482402Y0046457
X0474528Y0046851
X0466654Y0046457
X0506024Y0052362
X0498150Y0051969
X0490276Y0052362
X0482402Y0051969
X0474528Y0052362
X0466654Y0051969
X0657047Y0008268
X0649173Y0007874
X0657047Y0013780
X0649173Y0013386
X0506024Y0008268
X0498150Y0007874
X0490276Y0008268
X0482402Y0007874
X0474528Y0008268
X0466654Y0007874
X0506024Y0013780
X0498150Y0013386
X0490276Y0013780
X0482402Y0013386
X0474528Y0013780
X0466654Y0013386
X0657047Y0019292
X0649173Y0018898
X0657047Y0024803
X0649173Y0024410
X0657047Y0030315
X0649173Y0029922
X0657047Y0035827
X0649173Y0035433
X0657047Y0041339
X0649173Y0040945
X0657047Y0046851
X0649173Y0046457
X0657047Y0052362
X0649173Y0051969
X0688543Y0019292
X0680669Y0018898
X0672795Y0019292
X0664921Y0018898
X0688543Y0024803
X0680669Y0024410
X0672795Y0024803
X0664921Y0024410
X0688543Y0030315
X0680669Y0029922
X0672795Y0030315
X0664921Y0029922
X0688543Y0035827
X0680669Y0035433
X0672795Y0035827
X0664921Y0035433
X0688543Y0041339
X0680669Y0040945
X0672795Y0041339
X0664921Y0040945
X0688543Y0046851
X0680669Y0046457
X0672795Y0046851
X0664921Y0046457
X0688543Y0052362
X0680669Y0051969
X0672795Y0052362
X0664921Y0051969
X0688543Y0008268
X0680669Y0007874
X0672795Y0008268
X0664921Y0007874
X0688543Y0013780
X0680669Y0013386
X0672795Y0013780
X0664921Y0013386
X1376103Y0008268
X1368229Y0007874
X1376103Y0013780
X1368229Y0013386
X1360355Y0019292
X1352481Y0018898
X1344607Y0019292
X1336733Y0018898
X1360355Y0024803
X1352481Y0024410
X1344607Y0024803
X1336733Y0024410
X1360355Y0030315
X1352481Y0029922
X1344607Y0030315
X1336733Y0029922
X1360355Y0035827
X1352481Y0035433
X1344607Y0035827
X1336733Y0035433
X1360355Y0041339
X1352481Y0040945
X1344607Y0041339
X1336733Y0040945
X1360355Y0046851
X1352481Y0046457
X1344607Y0046851
X1336733Y0046457
X1360355Y0052362
X1352481Y0051969
X1344607Y0052362
X1336733Y0051969
X1360355Y0008268
X1352481Y0007874
X1344607Y0008268
X1336733Y0007874
X1360355Y0013780
X1352481Y0013386
X1344607Y0013780
X1336733Y0013386
X1376103Y0019292
X1368229Y0018898
X1376103Y0024803
X1368229Y0024410
X1376103Y0030315
X1368229Y0029922
X1376103Y0035827
X1368229Y0035433
X1376103Y0041339
X1368229Y0040945
X1376103Y0046851
X1368229Y0046457
X1376103Y0052362
X1368229Y0051969
X1558622Y0019292
X1550748Y0018898
X1542874Y0019292
X1535000Y0018898
X1527126Y0019292
X1519252Y0018898
X1558622Y0024803
X1550748Y0024410
X1542874Y0024803
X1535000Y0024410
X1527126Y0024803
X1519252Y0024410
X1558622Y0030315
X1550748Y0029922
X1542874Y0030315
X1535000Y0029922
X1527126Y0030315
X1519252Y0029922
X1558622Y0035827
X1550748Y0035433
X1542874Y0035827
X1535000Y0035433
X1527126Y0035827
X1519252Y0035433
X1558622Y0041339
X1550748Y0040945
X1542874Y0041339
X1535000Y0040945
X1527126Y0041339
X1519252Y0040945
X1558622Y0046851
X1550748Y0046457
X1542874Y0046851
X1535000Y0046457
X1527126Y0046851
X1519252Y0046457
X1558622Y0052362
X1550748Y0051969
X1542874Y0052362
X1535000Y0051969
X1527126Y0052362
X1519252Y0051969
X1558622Y0008268
X1550748Y0007874
X1542874Y0008268
X1535000Y0007874
X1527126Y0008268
X1519252Y0007874
X1558622Y0013780
X1550748Y0013386
X1542874Y0013780
X1535000Y0013386
X1527126Y0013780
X1519252Y0013386
M00
X0053200Y0169500
X0062200Y0169900
X0051900Y0162300
X0057200Y0165300
X0127400Y0170400
X0148600Y0170100
X0152600Y0152000
X0137000Y0170400
X0137100Y0158600
X0148000Y0158800
X0162000Y0159400
X0144700Y0149200
X0156500Y0144800
X0163200Y0151600
X0156000Y0138200
X0155900Y0170000
X0134800Y0164000
X0149300Y0164100
X0162100Y0164300
X0141900Y0154700
X0155600Y0157900
X0150300Y0144600
X0163500Y0144900
X0098000Y0157100
X0070400Y0170000
X0096900Y0169500
X0115300Y0170200
X0078200Y0169900
X0118400Y0152000
X0094900Y0144500
X0108600Y0143100
X0083500Y0169700
X0106500Y0170300
X0110900Y0159200
X0088000Y0158900
X0073200Y0162100
X0089000Y0150200
X0104500Y0150300
X0126600Y0149500
X0119900Y0143200
X0129200Y0142400
X0118100Y0162100
X0100700Y0163400
X0092600Y0154800
X0081600Y0162600
X0065600Y0160400
X0090200Y0169500
X0093900Y0162900
X0111900Y0164800
X0120500Y0157200
X0114000Y0145200
X0078800Y0158000
X0099000Y0148900
X0104900Y0157400
X0111800Y0151800
X0083800Y0154500
X0102000Y0141900
X0144200Y0096300
X0123100Y0049600
X0153100Y0049600
X0150300Y0020200
X0144500Y0040000
X0143800Y0053600
X0143300Y0027300
X0148800Y0085000
X0133100Y0071300
X0143000Y0105700
X0144100Y0072900
X0151500Y0035800
X0129200Y0101300
X0161800Y0086800
X0121200Y0033900
X0076900Y0020200
X0107200Y0019300
X0158200Y0102400
X0159800Y0065100
X0138700Y0063500
X0131400Y0091300
X0139800Y0090200
X0102500Y0029400
X0123900Y0041000
X0090200Y0022400
X0174200Y0096300
X0204200Y0096300
X0234200Y0096300
X0183100Y0049600
X0213100Y0049600
X0243100Y0049600
X0180300Y0020200
X0210300Y0020200
X0240300Y0020200
X0166500Y0034700
X0227100Y0043000
X0209400Y0060900
X0175000Y0062300
X0191700Y0075400
X0225600Y0104500
X0262900Y0104900
X0196200Y0102300
X0174300Y0073300
X0206700Y0072700
X0254400Y0074300
X0184100Y0036600
X0214700Y0035800
X0244900Y0036600
X0181400Y0084700
X0195600Y0064100
X0197800Y0048000
X0197800Y0030900
X0168100Y0048400
X0229200Y0030900
X0254400Y0019200
X0225800Y0019600
X0194400Y0020200
X0165600Y0019400
X0216400Y0100500
X0251600Y0100100
X0257800Y0051200
X0164400Y0138200
X0197300Y0139100
X0224400Y0138200
X0254400Y0138200
X0163800Y0170100
X0177800Y0170400
X0182600Y0152000
X0252600Y0192000
X0242300Y0171800
X0248400Y0149800
X0221800Y0149400
X0169900Y0146800
X0190400Y0169800
X0173700Y0158700
X0194600Y0154800
X0197100Y0160800
X0213500Y0155400
X0213300Y0146800
X0195900Y0146300
X0185800Y0145400
X0173600Y0138700
X0204200Y0139200
X0218100Y0140500
X0231600Y0155100
X0171300Y0170000
X0175500Y0151300
X0176300Y0164400
X0192100Y0163500
X0201500Y0154400
X0168000Y0161200
X0230600Y0146400
X0234500Y0138700
X0242600Y0140100
X0238800Y0157500
X0236800Y0165000
X0245600Y0157000
X0248600Y0142900
X0255400Y0148400
X0245100Y0165200
X0235400Y0172900
X0169400Y0153600
X0184000Y0138800
X0178100Y0144600
X0187100Y0155800
X0179300Y0156400
X0190000Y0149800
X0205100Y0147700
X0211300Y0138600
X0239600Y0148700
X0243300Y0185600
X0236500Y0185900
X0242400Y0193300
X0239800Y0178700
X0191200Y0142400
X0190400Y0136600
X0252800Y0179900
X0252200Y0159400
X0284400Y0138200
X0310200Y0135900
X0282600Y0192000
X0265300Y0170000
X0292800Y0169800
X0287600Y0150000
X0338300Y0183800
X0338300Y0162900
X0359100Y0184400
X0359200Y0164900
X0281000Y0180700
X0350200Y0181100
X0280000Y0159800
X0350000Y0161800
X0267700Y0145200
X0300300Y0140000
X0264200Y0096300
X0294200Y0096300
X0324200Y0096300
X0273100Y0049600
X0270300Y0020200
X0314600Y0104100
X0283600Y0069500
X0268300Y0036200
X0281800Y0100900
X0307800Y0101100
X0273300Y0094900
X0825200Y0111700
X0855200Y0111700
X0810700Y0065200
X0840700Y0065200
X0806800Y0026700
X0836800Y0026700
X0809700Y0086500
X0839700Y0086500
X0813700Y0043900
X0855400Y0173000
X0855400Y0152400
X0838300Y0128100
X0857000Y0189800
X0885400Y0173000
X0915400Y0173000
X0945400Y0173000
X0885400Y0152400
X0915400Y0152400
X0945400Y0152400
X0868300Y0128100
X0898300Y0128100
X0928300Y0128100
X0958300Y0128100
X0887000Y0189800
X0917000Y0189800
X0947000Y0189800
X0885200Y0111700
X0915200Y0111700
X0945200Y0111700
X0870700Y0065200
X0900700Y0065200
X0930700Y0065200
X0960700Y0065200
X0866800Y0026700
X0896800Y0026700
X0926800Y0026700
X0956800Y0026700
X0869700Y0086500
X0899700Y0086500
X0929700Y0086500
X0959700Y0086500
X1063700Y0015300
X0975200Y0111700
X1005200Y0111700
X1037200Y0111300
X0990700Y0065200
X1022700Y0064800
X1052700Y0064800
X0986800Y0026700
X1018800Y0026300
X1048800Y0026300
X0989700Y0086500
X1031900Y0084100
X1061900Y0084100
X1043000Y0045500
X0959000Y0018000
X0975400Y0173000
X1005400Y0173000
X1035400Y0173000
X0975400Y0152400
X1005400Y0152400
X1035400Y0152400
X0988300Y0128100
X1018300Y0128100
X1048300Y0128100
X0977000Y0189800
X1007000Y0189800
X1037000Y0189800
X1067400Y0172600
X1097400Y0172600
X1127400Y0172600
X1157400Y0172600
X1065400Y0152400
X1095400Y0152400
X1125400Y0152400
X1155400Y0152400
X1078300Y0128100
X1108300Y0128100
X1067000Y0189800
X1097000Y0189800
X1127000Y0189800
X1157000Y0189800
X1067200Y0111300
X1097200Y0111300
X1127200Y0111300
X1082700Y0064800
X1078800Y0026300
X1136600Y0019700
X1135400Y0041000
X1091900Y0084100
X1121900Y0084100
X1151900Y0084100
X1073000Y0045500
X1120900Y0064500
X1147100Y0064500
M00
X0004287Y0018504
X0008221Y0009008
X0017717Y0005074
X0027213Y0009008
X0031147Y0018504
X0027213Y0028000
X0017717Y0031934
X0008221Y0028000
X1657082Y0018504
X1661016Y0009008
X1661016Y0028000
X1680008Y0028000
X1670512Y0031934
X1670512Y0005074
X1680008Y0009008
X1683942Y0018504
M00
X0335906Y0059054
X0335906Y0051180
X0335906Y0043306
X0343780Y0059054
X0343780Y0051180
X0343780Y0043306
X0359528Y0059054
X0359528Y0051180
X0359528Y0043306
X0359528Y0027558
X0359528Y0019684
X0367402Y0011810
X0335906Y0027558
X0335906Y0019684
X0343780Y0027558
X0343780Y0019684
X0367402Y0059054
X0367402Y0051180
X0367402Y0043306
X0359528Y0011810
X0367402Y0027558
X0367402Y0019684
X0335906Y0011810
X0343780Y0011810
X1229606Y0011810
X1237480Y0011810
X1205984Y0011810
X1213858Y0011810
X1205984Y0059054
X1205984Y0051180
X1205984Y0043306
X1213858Y0059054
X1213858Y0051180
X1213858Y0043306
X1229606Y0059054
X1229606Y0051180
X1229606Y0043306
X1237480Y0059054
X1237480Y0051180
X1237480Y0043306
X1229606Y0027558
X1229606Y0019684
X1237480Y0027558
X1237480Y0019684
X1205984Y0027558
X1205984Y0019684
X1213858Y0027558
X1213858Y0019684
M00
X0439744Y0060217
X0589036Y0060217
X1309823Y0060217
X1459114Y0060217
M00
X0503859Y0151650
X0498859Y0141650
X0493859Y0151650
X0488859Y0141650
X0483859Y0151650
X0478859Y0141650
X0473859Y0151650
X0468859Y0141650
X0473859Y0125666
X0483859Y0125666
X0493859Y0125666
X0503859Y0125666
X0468859Y0115666
X0478859Y0115666
X0488859Y0115666
X0498859Y0115666
X1358938Y0141650
X1353938Y0151650
X1348938Y0141650
X1343938Y0151650
X1338938Y0141650
X1343938Y0125666
X1353938Y0125666
X1338938Y0115666
X1348938Y0115666
X1358938Y0115666
X1368938Y0115666
X1373938Y0151650
X1368938Y0141650
X1363938Y0151650
X1363938Y0125666
X1373938Y0125666
M00
X0439744Y0088564
X0439744Y0070060
X0439744Y0050375
X0430571Y0032264
X0411673Y0032264
X0392776Y0032264
X0383642Y0088564
X0383642Y0070060
X0383642Y0050375
X0560965Y0032264
X0542068Y0032264
X0532934Y0088564
X0532934Y0070060
X0532934Y0050375
X0589036Y0088564
X0589036Y0070060
X0589036Y0050375
X0579863Y0032264
X1262855Y0032264
X1253721Y0088564
X1253721Y0070060
X1253721Y0050375
X1309823Y0088564
X1309823Y0070060
X1309823Y0050375
X1300650Y0032264
X1281752Y0032264
X1459114Y0088564
X1459114Y0070060
X1459114Y0050375
X1449941Y0032264
X1431043Y0032264
X1412146Y0032264
X1403012Y0088564
X1403012Y0070060
X1403012Y0050375
M00
X0089803Y0068898
X0089803Y0076772
X0089803Y0084646
X0089803Y0092520
X0089803Y0100394
X0089803Y0108268
X0081929Y0068898
X0081929Y0076772
X0081929Y0084646
X0081929Y0092520
X0081929Y0100394
X0081929Y0108268
M00
X0383642Y0040532
X0439744Y0099587
X0417382Y0099587
X0396122Y0099587
X0383642Y0079902
X0439744Y0178327
X0405964Y0178327
X0439744Y0138957
X0383642Y0158642
X0383642Y0119272
X0555256Y0178327
X0532934Y0158642
X0532934Y0119272
X0532934Y0040532
X0545414Y0099587
X0532934Y0079902
X0589036Y0099587
X0566674Y0099587
X0589036Y0178327
X0589036Y0138957
X1253721Y0040532
X1253721Y0079902
X1253721Y0158642
X1253721Y0119272
X1309823Y0178327
X1276043Y0178327
X1309823Y0138957
X1309823Y0099587
X1287461Y0099587
X1266201Y0099587
X1403012Y0040532
X1459114Y0099587
X1436752Y0099587
X1415492Y0099587
X1403012Y0079902
X1459114Y0178327
X1425334Y0178327
X1459114Y0138957
X1403012Y0158642
X1403012Y0119272
M00
X0056339Y0112205
X0056339Y0100394
X0056339Y0088583
X0056339Y0076772
X0056339Y0064961
X0056339Y0053150
X0056339Y0041339
X0044528Y0112205
X0044528Y0100394
X0044528Y0088583
X0044528Y0076772
X0044528Y0064961
X0044528Y0053150
X0044528Y0041339
X0056339Y0135827
X0056339Y0124016
X0044528Y0135827
X0044528Y0124016
M00
X0019088Y0091958
X0009088Y0091958
X0019088Y0080158
X0009088Y0080158
X0119288Y0103958
X0109288Y0103958
X0119288Y0092458
X0109288Y0092458
M00
X0641212Y0132244
X0791764Y0132244
X1511291Y0132244
X1661843Y0132244
M00
X0452875Y0194642
X0455867Y0153658
X0452875Y0131650
X0516851Y0140666
X0519843Y0194642
X0519843Y0115666
X1322954Y0194642
X1325946Y0153658
X1322954Y0131650
X1389922Y0115666
X1386930Y0140666
X1389922Y0194642
M00
X0639283Y0108622
X0639283Y0167677
X0793693Y0108622
X0793693Y0167677
X1509362Y0167677
X1509362Y0108622
X1663772Y0167677
X1663772Y0108622
M00
X0306772Y0041850
X0306772Y0067913
X0306772Y0019685
X0612047Y0041850
X0612047Y0067913
X0612047Y0019685
X1176851Y0041850
X1176851Y0067913
X1176851Y0019685
X1482126Y0041850
X1482126Y0067913
X1482126Y0019685
M00
X0085866Y0104331
X0085866Y0072835
M00
X0040827Y0029528
X0040827Y0147638
M00
X0392795Y0056653
X0542087Y0056654
X0655453Y0132244
X0730295Y0132244
X0702697Y0132244
X0777539Y0132244
X1262874Y0056654
X1412166Y0056653
X1525531Y0132244
X1600374Y0132244
X1647618Y0132244
X1572775Y0132244
M00
X0351654Y0037400
X1221732Y0037400
M00
X0463859Y0176650
X0508859Y0176650
X1333938Y0176650
X1378938Y0176650
M00
X0017716Y0114173
X0314213Y0163386
X0783661Y0018504
X0826024Y0163386
X1101615Y0018504
X1184292Y0163386
M00
X0017717Y0018504
X1670512Y0018504
M30
